FILE_TYPE = CONNECTIVITY;
{Allegro Design Entry HDL 17.2-2016 S081 (4005846) 1/11/2022}
"PAGE_NUMBER" = 87;
0"NC";
1"P12V_S3_AUX_CPU0_NVDIMM\g";
2"P3V3_AUX\g";
3"P12V_S3_AUX_CPU0_NVDIMM\g";
4"P3V3_AUX\g";
5"GND\g";
6"GND\g";
7"GND\g";
8"GND\g";
9"GND\g";
10"M_C_CPU0_SA_DQ<31:0>";
11"M_C_CPU0_SA_CB<7:0>";
12"M_C_CPU0_SB_CB<7:0>";
13"M_C_CPU0_SA_CA<6:0>";
14"M_C_CPU0_SB_CA<6:0>";
15"M_C_CPU0_SB_DQ<31:0>";
16"M_C_CPU0_SB_DQS_DP<9:0>";
17"M_C_CPU0_SA_DQS_DP<9:0>";
18"M_C_CPU0_SB_DQS_DN<9:0>";
19"M_C_CPU0_SA_DQS_DN<9:0>";
20"PD_CHC_CPU0_DIMM2_SAA";
21"I3C_SPD_DDRABCD_CPU0_LVC1_SDA";
22"I3C_SPD_DDRABCD_CPU0_LVC1_SCL_R6";
23"M_C_CPU0_ALERT_N";
24"RST_M_CD_CPU0_FPGA_N";
25"I3C_SPD_DDRABCD_CPU0_LVC1_SCL";
26"TP_CHC_CPU0_DIMM2_FRU_4";
27"TP_CHC_CPU0_DIMM2_FRU_5";
28"PWRGD_CHC_CPU0_DIMM2";
29"M_C_CPU0_SB_CS_N<2>";
30"M_C_CPU0_SB_DQS_DN<6>";
31"M_C_CPU0_SA_DQS_DN<9>";
32"M_C_CPU0_SA_DQS_DN<8>";
33"M_C_CPU0_SA_DQS_DN<6>";
34"M_C_CPU0_SA_DQS_DN<7>";
35"M_C_CPU0_SA_DQS_DN<5>";
36"M_C_CPU0_SA_DQS_DN<4>";
37"M_C_CPU0_SA_DQS_DN<3>";
38"M_C_CPU0_SA_DQS_DN<1>";
39"M_C_CPU0_SA_DQS_DN<2>";
40"M_C_CPU0_SA_DQS_DN<0>";
41"M_C_CPU0_SB_DQS_DN<9>";
42"M_C_CPU0_SB_DQS_DN<8>";
43"M_C_CPU0_SB_DQS_DN<7>";
44"M_C_CPU0_SB_DQS_DN<5>";
45"M_C_CPU0_SB_DQS_DN<4>";
46"M_C_CPU0_SB_DQS_DN<3>";
47"M_C_CPU0_SB_DQS_DN<2>";
48"M_C_CPU0_SB_DQS_DN<0>";
49"M_C_CPU0_SB_DQS_DN<1>";
50"M_C_CPU0_SA_DQS_DP<9>";
51"M_C_CPU0_SA_DQS_DP<8>";
52"M_C_CPU0_SA_DQS_DP<7>";
53"M_C_CPU0_SA_DQS_DP<6>";
54"M_C_CPU0_SA_DQS_DP<5>";
55"M_C_CPU0_SA_DQS_DP<4>";
56"M_C_CPU0_SA_DQS_DP<3>";
57"M_C_CPU0_SA_DQS_DP<2>";
58"M_C_CPU0_SA_DQS_DP<1>";
59"M_C_CPU0_SA_DQS_DP<0>";
60"M_C_CPU0_SB_DQS_DP<9>";
61"M_C_CPU0_SB_DQS_DP<8>";
62"M_C_CPU0_SB_DQS_DP<7>";
63"M_C_CPU0_SB_DQS_DP<6>";
64"M_C_CPU0_SB_DQS_DP<5>";
65"M_C_CPU0_SB_DQS_DP<4>";
66"M_C_CPU0_SB_DQS_DP<3>";
67"M_C_CPU0_SB_DQS_DP<2>";
68"M_C_CPU0_SB_DQS_DP<1>";
69"M_C_CPU0_SB_DQS_DP<0>";
70"M_C_CPU0_CLK_DP<1>";
71"TP_CHC_CPU0_DIMM2_FRU_3";
72"TP_CHC_CPU0_DIMM2_FRU_2";
73"TP_CHC_CPU0_DIMM2_FRU_0";
74"TP_CHC_CPU0_DIMM2_FRU_6";
75"M_C_CPU0_SB_DQ<7>";
76"M_C_CPU0_SB_CA<1>";
77"M_C_CPU0_SA_PAR";
78"M_C_CPU0_SB_PAR";
79"M_C_CPU0_SA_CS_N<3>";
80"M_C_CPU0_SA_CS_N<2>";
81"M_C_CPU0_SB_CS_N<3>";
82"M_C_CPU0_CLK_DN<1>";
83"M_C_CPU0_SB_CB<4>";
84"M_C_CPU0_SB_CB<5>";
85"M_C_CPU0_SB_DQ<20>";
86"M_C_CPU0_SB_DQ<6>";
87"TP_CHC_CPU0_DIMM2_FRU_1";
88"M_C_CPU0_SB_RSP<1>";
89"M_C_CPU0_SA_RSP<1>";
90"M_C_CPU0_SB_DQ<0>";
91"M_C_CPU0_SB_DQ<1>";
92"M_C_CPU0_SB_DQ<2>";
93"M_C_CPU0_SB_DQ<3>";
94"M_C_CPU0_SB_DQ<4>";
95"M_C_CPU0_SB_DQ<5>";
96"M_C_CPU0_SB_DQ<8>";
97"M_C_CPU0_SB_DQ<9>";
98"M_C_CPU0_SB_DQ<10>";
99"M_C_CPU0_SB_DQ<11>";
100"M_C_CPU0_SB_DQ<12>";
101"M_C_CPU0_SB_DQ<13>";
102"M_C_CPU0_SB_DQ<14>";
103"M_C_CPU0_SB_DQ<15>";
104"M_C_CPU0_SB_DQ<16>";
105"M_C_CPU0_SB_DQ<17>";
106"M_C_CPU0_SB_DQ<18>";
107"M_C_CPU0_SB_DQ<19>";
108"M_C_CPU0_SB_DQ<21>";
109"M_C_CPU0_SB_DQ<22>";
110"M_C_CPU0_SB_DQ<23>";
111"M_C_CPU0_SB_DQ<24>";
112"M_C_CPU0_SB_DQ<25>";
113"M_C_CPU0_SB_DQ<26>";
114"M_C_CPU0_SB_DQ<27>";
115"M_C_CPU0_SB_DQ<28>";
116"M_C_CPU0_SB_DQ<29>";
117"M_C_CPU0_SB_DQ<30>";
118"M_C_CPU0_SB_DQ<31>";
119"M_C_CPU0_SA_DQ<0>";
120"M_C_CPU0_SA_DQ<1>";
121"M_C_CPU0_SA_DQ<2>";
122"M_C_CPU0_SA_DQ<3>";
123"M_C_CPU0_SA_DQ<4>";
124"M_C_CPU0_SA_DQ<5>";
125"M_C_CPU0_SA_DQ<6>";
126"M_C_CPU0_SA_DQ<7>";
127"M_C_CPU0_SA_DQ<8>";
128"M_C_CPU0_SA_DQ<9>";
129"M_C_CPU0_SA_DQ<10>";
130"M_C_CPU0_SA_DQ<11>";
131"M_C_CPU0_SA_DQ<12>";
132"M_C_CPU0_SA_DQ<13>";
133"M_C_CPU0_SA_DQ<14>";
134"M_C_CPU0_SA_DQ<15>";
135"M_C_CPU0_SA_DQ<16>";
136"M_C_CPU0_SA_DQ<17>";
137"M_C_CPU0_SA_DQ<18>";
138"M_C_CPU0_SA_DQ<19>";
139"M_C_CPU0_SA_DQ<20>";
140"M_C_CPU0_SA_DQ<21>";
141"M_C_CPU0_SA_DQ<22>";
142"M_C_CPU0_SA_DQ<23>";
143"M_C_CPU0_SA_DQ<24>";
144"M_C_CPU0_SA_DQ<25>";
145"M_C_CPU0_SA_DQ<26>";
146"M_C_CPU0_SA_DQ<27>";
147"M_C_CPU0_SA_DQ<28>";
148"M_C_CPU0_SA_DQ<29>";
149"M_C_CPU0_SA_DQ<30>";
150"M_C_CPU0_SB_CB<0>";
151"M_C_CPU0_SB_CB<1>";
152"M_C_CPU0_SB_CB<2>";
153"M_C_CPU0_SB_CB<3>";
154"M_C_CPU0_SB_CB<6>";
155"M_C_CPU0_SA_CB<0>";
156"M_C_CPU0_SA_CB<2>";
157"M_C_CPU0_SA_CB<3>";
158"M_C_CPU0_SA_CB<5>";
159"M_C_CPU0_SA_CB<6>";
160"M_C_CPU0_SB_CA<6>";
161"M_C_CPU0_SA_CA<6>";
162"M_C_CPU0_SB_CA<5>";
163"M_C_CPU0_SA_CA<5>";
164"M_C_CPU0_SB_CA<4>";
165"M_C_CPU0_SA_CA<4>";
166"M_C_CPU0_SB_CA<3>";
167"M_C_CPU0_SA_CA<3>";
168"M_C_CPU0_SB_CA<2>";
169"M_C_CPU0_SA_CA<2>";
170"M_C_CPU0_SA_CA<1>";
171"M_C_CPU0_SB_CA<0>";
172"M_C_CPU0_SA_CA<0>";
173"M_C_CPU0_SB_CB<7>";
174"M_C_CPU0_SA_CB<1>";
175"M_C_CPU0_SA_CB<4>";
176"M_C_CPU0_SA_CB<7>";
177"M_C_CPU0_SA_DQ<31>";
178"PD_CHC_CPU0_DIMM2_SAA";
%"TAP"
"1","(-450,3700)","0","standard","I100";
;
CDS_LIB"standard"
BODY_TYPE"PLUMBING"
HDL_TAP"TRUE";
"B \NAC \NWC"10;
"S \NAC"
BN"21"140;
%"TAP"
"1","(-450,3750)","0","standard","I101";
;
CDS_LIB"standard"
BODY_TYPE"PLUMBING"
HDL_TAP"TRUE";
"B \NAC \NWC"10;
"S \NAC"
BN"22"141;
%"TAP"
"1","(-450,3850)","0","standard","I102";
;
CDS_LIB"standard"
BODY_TYPE"PLUMBING"
HDL_TAP"TRUE";
"B \NAC \NWC"10;
"S \NAC"
BN"24"143;
%"TAP"
"1","(-450,3800)","0","standard","I103";
;
CDS_LIB"standard"
BODY_TYPE"PLUMBING"
HDL_TAP"TRUE";
"B \NAC \NWC"10;
"S \NAC"
BN"23"142;
%"TAP"
"1","(-2100,3950)","2","standard","I105";
;
CDS_LIB"standard"
BODY_TYPE"PLUMBING"
HDL_TAP"TRUE";
"B \NAC \NWC"13;
"S \NAC"
BN"1"170;
%"TAP"
"1","(-2100,3900)","2","standard","I106";
;
CDS_LIB"standard"
BODY_TYPE"PLUMBING"
HDL_TAP"TRUE";
"B \NAC \NWC"13;
"S \NAC"
BN"0"172;
%"TAP"
"1","(-2100,4100)","2","standard","I107";
;
CDS_LIB"standard"
BODY_TYPE"PLUMBING"
HDL_TAP"TRUE";
"B \NAC \NWC"13;
"S \NAC"
BN"4"165;
%"TAP"
"1","(-2100,4050)","2","standard","I108";
;
CDS_LIB"standard"
BODY_TYPE"PLUMBING"
HDL_TAP"TRUE";
"B \NAC \NWC"13;
"S \NAC"
BN"3"167;
%"TAP"
"1","(-2100,4000)","2","standard","I109";
;
CDS_LIB"standard"
BODY_TYPE"PLUMBING"
HDL_TAP"TRUE";
"B \NAC \NWC"13;
"S \NAC"
BN"2"169;
%"TAP"
"1","(-2100,4150)","2","standard","I110";
;
CDS_LIB"standard"
BODY_TYPE"PLUMBING"
HDL_TAP"TRUE";
"B \NAC \NWC"13;
"S \NAC"
BN"5"163;
%"TAP"
"1","(-2100,4200)","2","standard","I111";
;
CDS_LIB"standard"
BODY_TYPE"PLUMBING"
HDL_TAP"TRUE";
"B \NAC \NWC"13;
"S \NAC"
BN"6"161;
%"TAP"
"1","(-450,3950)","0","standard","I112";
;
CDS_LIB"standard"
BODY_TYPE"PLUMBING"
HDL_TAP"TRUE";
"B \NAC \NWC"10;
"S \NAC"
BN"26"145;
%"TAP"
"1","(-450,3900)","0","standard","I113";
;
CDS_LIB"standard"
BODY_TYPE"PLUMBING"
HDL_TAP"TRUE";
"B \NAC \NWC"10;
"S \NAC"
BN"25"144;
%"TAP"
"1","(-450,4000)","0","standard","I114";
;
CDS_LIB"standard"
BODY_TYPE"PLUMBING"
HDL_TAP"TRUE";
"B \NAC \NWC"10;
"S \NAC"
BN"27"146;
%"TAP"
"1","(-450,4050)","0","standard","I115";
;
CDS_LIB"standard"
BODY_TYPE"PLUMBING"
HDL_TAP"TRUE";
"B \NAC \NWC"10;
"S \NAC"
BN"28"147;
%"TAP"
"1","(-450,4100)","0","standard","I116";
;
CDS_LIB"standard"
BODY_TYPE"PLUMBING"
HDL_TAP"TRUE";
"B \NAC \NWC"10;
"S \NAC"
BN"29"148;
%"TAP"
"1","(-450,4150)","0","standard","I117";
;
CDS_LIB"standard"
BODY_TYPE"PLUMBING"
HDL_TAP"TRUE";
"B \NAC \NWC"10;
"S \NAC"
BN"30"149;
%"TAP"
"1","(-450,4200)","0","standard","I118";
;
CDS_LIB"standard"
BODY_TYPE"PLUMBING"
HDL_TAP"TRUE";
"B \NAC \NWC"10;
"S \NAC"
BN"31"177;
%"UNIVERSAL_GND"
"1","(1275,-50)","0","logical_power","I119";
;
CDS_LIB"logical_power"
HDL_POWER"GND";
"A"9;
%"Q_CAP"
"1","(1275,325)","0","pure_quanta","I120";
;
PART_NUMBER"CH5221MEB00"
VOLTAGE"6.3V"
MATERIAL"X6S"
TOLERANCE"20%"
VALUE"2.2UF"
PACK_TYPE"C0402"
$LOCATION"C17"
CDS_LIB"pure_quanta"
CDS_LOCATION"C17"
$SEC"1"
CDS_SEC"1";
"B"
$PN"2"9;
"A"
$PN"1"4;
%"VCC_CORE"
"1","(1275,650)","0","logical_power","I121";
;
HDL_POWER"P3V3_AUX"
CDS_LIB"logical_power";
"A"4;
%"Q_CAP"
"1","(2275,325)","0","pure_quanta","I124";
;
PART_NUMBER"CH6103KEA00"
PACK_TYPE"C0805"
MATERIAL"X6S"
VALUE"10UF"
VOLTAGE"16V"
TOLERANCE"10%"
$LOCATION"C18"
CDS_LIB"pure_quanta"
CDS_LOCATION"C18"
$SEC"1"
CDS_SEC"1";
"B"
$PN"2"8;
"A"
$PN"1"1;
%"VCC_CORE"
"1","(2275,650)","0","logical_power","I125";
;
HDL_POWER"P12V_S3_AUX_CPU0_NVDIMM"
CDS_LIB"logical_power";
"A"1;
%"UNIVERSAL_GND"
"1","(2900,-50)","0","logical_power","I126";
;
CDS_LIB"logical_power"
HDL_POWER"GND";
"A"8;
%"Q_CAP"
"1","(2900,325)","0","pure_quanta","I127";
;
PART_NUMBER"CH6103KEA00"
TOLERANCE"10%"
VALUE"10UF"
PACK_TYPE"C0805"
VOLTAGE"16V"
MATERIAL"X6S"
$LOCATION"C19"
CDS_LIB"pure_quanta"
CDS_LOCATION"C19"
$SEC"1"
CDS_SEC"1";
"B"
$PN"2"8;
"A"
$PN"1"1;
%"UNIVERSAL_GND"
"1","(3975,500)","0","logical_power","I128";
;
CDS_LIB"logical_power"
HDL_POWER"GND";
"A"7;
%"TAP"
"1","(2300,2350)","0","standard","I129";
;
CDS_LIB"standard"
BODY_TYPE"PLUMBING"
HDL_TAP"TRUE";
"B \NAC \NWC"16;
"S \NAC"
BN"1"68;
%"TAP"
"1","(2300,2250)","0","standard","I130";
;
CDS_LIB"standard"
BODY_TYPE"PLUMBING"
HDL_TAP"TRUE";
"B \NAC \NWC"16;
"S \NAC"
BN"0"69;
%"TAP"
"1","(2475,2200)","0","standard","I131";
;
CDS_LIB"standard"
BODY_TYPE"PLUMBING"
HDL_TAP"TRUE";
"B \NAC \NWC"18;
"S \NAC"
BN"0"48;
%"TAP"
"1","(2475,2300)","0","standard","I132";
;
CDS_LIB"standard"
BODY_TYPE"PLUMBING"
HDL_TAP"TRUE";
"B \NAC \NWC"18;
"S \NAC"
BN"1"49;
%"TAP"
"1","(2300,2550)","0","standard","I133";
;
CDS_LIB"standard"
BODY_TYPE"PLUMBING"
HDL_TAP"TRUE";
"B \NAC \NWC"16;
"S \NAC"
BN"3"66;
%"TAP"
"1","(2300,2450)","0","standard","I134";
;
CDS_LIB"standard"
BODY_TYPE"PLUMBING"
HDL_TAP"TRUE";
"B \NAC \NWC"16;
"S \NAC"
BN"2"67;
%"TAP"
"1","(2475,2400)","0","standard","I135";
;
CDS_LIB"standard"
BODY_TYPE"PLUMBING"
HDL_TAP"TRUE";
"B \NAC \NWC"18;
"S \NAC"
BN"2"47;
%"TAP"
"1","(2475,2500)","0","standard","I136";
;
CDS_LIB"standard"
BODY_TYPE"PLUMBING"
HDL_TAP"TRUE";
"B \NAC \NWC"18;
"S \NAC"
BN"3"46;
%"TAP"
"1","(2475,2600)","0","standard","I137";
;
CDS_LIB"standard"
BODY_TYPE"PLUMBING"
HDL_TAP"TRUE";
"B \NAC \NWC"18;
"S \NAC"
BN"4"45;
%"TAP"
"1","(2300,2650)","0","standard","I138";
;
CDS_LIB"standard"
BODY_TYPE"PLUMBING"
HDL_TAP"TRUE";
"B \NAC \NWC"16;
"S \NAC"
BN"4"65;
%"TAP"
"1","(2300,2750)","0","standard","I139";
;
CDS_LIB"standard"
BODY_TYPE"PLUMBING"
HDL_TAP"TRUE";
"B \NAC \NWC"16;
"S \NAC"
BN"5"64;
%"TAP"
"1","(2300,2850)","0","standard","I140";
;
CDS_LIB"standard"
BODY_TYPE"PLUMBING"
HDL_TAP"TRUE";
"B \NAC \NWC"16;
"S \NAC"
BN"6"63;
%"TAP"
"1","(2475,2700)","0","standard","I141";
;
CDS_LIB"standard"
BODY_TYPE"PLUMBING"
HDL_TAP"TRUE";
"B \NAC \NWC"18;
"S \NAC"
BN"5"44;
%"TAP"
"1","(2475,2800)","0","standard","I142";
;
CDS_LIB"standard"
BODY_TYPE"PLUMBING"
HDL_TAP"TRUE";
"B \NAC \NWC"18;
"S \NAC"
BN"6"30;
%"TAP"
"1","(2300,3050)","0","standard","I143";
;
CDS_LIB"standard"
BODY_TYPE"PLUMBING"
HDL_TAP"TRUE";
"B \NAC \NWC"16;
"S \NAC"
BN"8"61;
%"TAP"
"1","(2300,2950)","0","standard","I144";
;
CDS_LIB"standard"
BODY_TYPE"PLUMBING"
HDL_TAP"TRUE";
"B \NAC \NWC"16;
"S \NAC"
BN"7"62;
%"TAP"
"1","(2475,2900)","0","standard","I145";
;
CDS_LIB"standard"
BODY_TYPE"PLUMBING"
HDL_TAP"TRUE";
"B \NAC \NWC"18;
"S \NAC"
BN"7"43;
%"TAP"
"1","(2475,3000)","0","standard","I146";
;
CDS_LIB"standard"
BODY_TYPE"PLUMBING"
HDL_TAP"TRUE";
"B \NAC \NWC"18;
"S \NAC"
BN"8"42;
%"TAP"
"1","(2475,3100)","0","standard","I147";
;
CDS_LIB"standard"
BODY_TYPE"PLUMBING"
HDL_TAP"TRUE";
"B \NAC \NWC"18;
"S \NAC"
BN"9"41;
%"TAP"
"1","(2300,3300)","0","standard","I148";
;
CDS_LIB"standard"
BODY_TYPE"PLUMBING"
HDL_TAP"TRUE";
"B \NAC \NWC"17;
"S \NAC"
BN"0"59;
%"TAP"
"1","(2300,3150)","0","standard","I149";
;
CDS_LIB"standard"
BODY_TYPE"PLUMBING"
HDL_TAP"TRUE";
"B \NAC \NWC"16;
"S \NAC"
BN"9"60;
%"TAP"
"1","(2475,3350)","0","standard","I150";
;
CDS_LIB"standard"
BODY_TYPE"PLUMBING"
HDL_TAP"TRUE";
"B \NAC \NWC"19;
"S \NAC"
BN"1"38;
%"TAP"
"1","(2475,3250)","0","standard","I151";
;
CDS_LIB"standard"
BODY_TYPE"PLUMBING"
HDL_TAP"TRUE";
"B \NAC \NWC"19;
"S \NAC"
BN"0"40;
%"TAP"
"1","(2300,3500)","0","standard","I152";
;
CDS_LIB"standard"
BODY_TYPE"PLUMBING"
HDL_TAP"TRUE";
"B \NAC \NWC"17;
"S \NAC"
BN"2"57;
%"TAP"
"1","(2300,3400)","0","standard","I153";
;
CDS_LIB"standard"
BODY_TYPE"PLUMBING"
HDL_TAP"TRUE";
"B \NAC \NWC"17;
"S \NAC"
BN"1"58;
%"TAP"
"1","(2300,3600)","0","standard","I154";
;
CDS_LIB"standard"
BODY_TYPE"PLUMBING"
HDL_TAP"TRUE";
"B \NAC \NWC"17;
"S \NAC"
BN"3"56;
%"TAP"
"1","(2475,3450)","0","standard","I155";
;
CDS_LIB"standard"
BODY_TYPE"PLUMBING"
HDL_TAP"TRUE";
"B \NAC \NWC"19;
"S \NAC"
BN"2"39;
%"TAP"
"1","(2475,3550)","0","standard","I156";
;
CDS_LIB"standard"
BODY_TYPE"PLUMBING"
HDL_TAP"TRUE";
"B \NAC \NWC"19;
"S \NAC"
BN"3"37;
%"TAP"
"1","(2300,3700)","0","standard","I157";
;
CDS_LIB"standard"
BODY_TYPE"PLUMBING"
HDL_TAP"TRUE";
"B \NAC \NWC"17;
"S \NAC"
BN"4"55;
%"TAP"
"1","(2300,3800)","0","standard","I158";
;
CDS_LIB"standard"
BODY_TYPE"PLUMBING"
HDL_TAP"TRUE";
"B \NAC \NWC"17;
"S \NAC"
BN"5"54;
%"TAP"
"1","(2475,3850)","0","standard","I159";
;
CDS_LIB"standard"
BODY_TYPE"PLUMBING"
HDL_TAP"TRUE";
"B \NAC \NWC"19;
"S \NAC"
BN"6"33;
%"TAP"
"1","(2475,3750)","0","standard","I160";
;
CDS_LIB"standard"
BODY_TYPE"PLUMBING"
HDL_TAP"TRUE";
"B \NAC \NWC"19;
"S \NAC"
BN"5"35;
%"TAP"
"1","(2475,3650)","0","standard","I161";
;
CDS_LIB"standard"
BODY_TYPE"PLUMBING"
HDL_TAP"TRUE";
"B \NAC \NWC"19;
"S \NAC"
BN"4"36;
%"TAP"
"1","(2300,4000)","0","standard","I165";
;
CDS_LIB"standard"
BODY_TYPE"PLUMBING"
HDL_TAP"TRUE";
"B \NAC \NWC"17;
"S \NAC"
BN"7"52;
%"TAP"
"1","(2300,3900)","0","standard","I166";
;
CDS_LIB"standard"
BODY_TYPE"PLUMBING"
HDL_TAP"TRUE";
"B \NAC \NWC"17;
"S \NAC"
BN"6"53;
%"TAP"
"1","(2300,4100)","0","standard","I167";
;
CDS_LIB"standard"
BODY_TYPE"PLUMBING"
HDL_TAP"TRUE";
"B \NAC \NWC"17;
"S \NAC"
BN"8"51;
%"TAP"
"1","(2475,3950)","0","standard","I168";
;
CDS_LIB"standard"
BODY_TYPE"PLUMBING"
HDL_TAP"TRUE";
"B \NAC \NWC"19;
"S \NAC"
BN"7"34;
%"TAP"
"1","(2475,4150)","0","standard","I169";
;
CDS_LIB"standard"
BODY_TYPE"PLUMBING"
HDL_TAP"TRUE";
"B \NAC \NWC"19;
"S \NAC"
BN"9"31;
%"TAP"
"1","(2475,4050)","0","standard","I170";
;
CDS_LIB"standard"
BODY_TYPE"PLUMBING"
HDL_TAP"TRUE";
"B \NAC \NWC"19;
"S \NAC"
BN"8"32;
%"TAP"
"1","(2300,4200)","0","standard","I171";
;
CDS_LIB"standard"
BODY_TYPE"PLUMBING"
HDL_TAP"TRUE";
"B \NAC \NWC"17;
"S \NAC"
BN"9"50;
%"VCC_CORE"
"1","(3975,4750)","0","logical_power","I174";
;
HDL_POWER"P12V_S3_AUX_CPU0_NVDIMM"
CDS_LIB"logical_power";
"A"3;
%"SCONN288_ADR50017P087CC"
"3","(4825,2575)","0","pure_quanta","I175";
;
PART_NUMBER"DFHST8FS460"
MATERIAL"IO"
PART_TYPE"SMLF"
VALUE"SCONN288_ADR50017-P087CC"
$LOCATION"J6"
NEEDS_NO_SIZE"TRUE"
CDS_LMAN_SYM_OUTLINE"-450,1775,450,-1775"
CDS_LIB"pure_quanta"
CDS_LOCATION"J6"
$SEC"3"
CDS_SEC"3";
"G3"
$PN"G3"6;
"G2"
$PN"G2"6;
"G1"
$PN"G1"6;
"VSS62"
$PN"141"6;
"VSS61"
$PN"139"6;
"VSS60"
$PN"136"6;
"VSS58"
$PN"132"6;
"VSS104"
$PN"240"7;
"VSS102"
$PN"235"7;
"VSS100"
$PN"230"7;
"VIN_BULK2"
$PN"146"3;
"VIN_BULK1"
$PN"145"3;
"VIN_BULK0"
$PN"1"3;
"VSS126"
$PN"288"7;
"VSS125"
$PN"286"7;
"VSS124"
$PN"284"7;
"VSS123"
$PN"281"7;
"VSS122"
$PN"279"7;
"VSS121"
$PN"277"7;
"VSS120"
$PN"275"7;
"VSS119"
$PN"273"7;
"VSS118"
$PN"270"7;
"VSS117"
$PN"268"7;
"VSS116"
$PN"266"7;
"VSS115"
$PN"264"7;
"VSS114"
$PN"262"7;
"VSS113"
$PN"259"7;
"VSS112"
$PN"257"7;
"VSS111"
$PN"255"7;
"VSS110"
$PN"253"7;
"VSS109"
$PN"251"7;
"VSS108"
$PN"248"7;
"VSS107"
$PN"246"7;
"VSS106"
$PN"244"7;
"VSS105"
$PN"242"7;
"VSS103"
$PN"237"7;
"VSS101"
$PN"233"7;
"VSS99"
$PN"228"7;
"VSS98"
$PN"226"7;
"VSS97"
$PN"224"7;
"VSS96"
$PN"222"7;
"VSS95"
$PN"219"7;
"VSS94"
$PN"216"7;
"VSS93"
$PN"214"7;
"VSS92"
$PN"212"7;
"VSS91"
$PN"210"7;
"VSS90"
$PN"208"7;
"VSS89"
$PN"206"7;
"VSS88"
$PN"204"7;
"VSS87"
$PN"202"7;
"VSS86"
$PN"199"7;
"VSS85"
$PN"197"7;
"VSS84"
$PN"195"7;
"VSS83"
$PN"193"7;
"VSS82"
$PN"191"7;
"VSS81"
$PN"188"7;
"VSS80"
$PN"186"7;
"VSS79"
$PN"184"7;
"VSS78"
$PN"182"7;
"VSS77"
$PN"180"7;
"VSS76"
$PN"177"7;
"VSS75"
$PN"175"7;
"VSS74"
$PN"173"7;
"VSS73"
$PN"171"7;
"VSS72"
$PN"169"7;
"VSS71"
$PN"166"7;
"VSS70"
$PN"164"7;
"VSS69"
$PN"162"7;
"VSS68"
$PN"160"7;
"VSS67"
$PN"158"7;
"VSS66"
$PN"155"7;
"VSS65"
$PN"153"7;
"VSS64"
$PN"151"7;
"VSS63"
$PN"143"6;
"VSS59"
$PN"134"6;
"VSS57"
$PN"130"6;
"VSS56"
$PN"128"6;
"VSS55"
$PN"125"6;
"VSS54"
$PN"123"6;
"VSS53"
$PN"121"6;
"VSS52"
$PN"119"6;
"VSS51"
$PN"117"6;
"VSS50"
$PN"114"6;
"VSS49"
$PN"112"6;
"VSS48"
$PN"110"6;
"VSS47"
$PN"108"6;
"VSS46"
$PN"106"6;
"VSS45"
$PN"103"6;
"VSS44"
$PN"101"6;
"VSS43"
$PN"99"6;
"VSS42"
$PN"97"6;
"VSS41"
$PN"95"6;
"VSS40"
$PN"92"6;
"VSS39"
$PN"90"6;
"VSS38"
$PN"88"6;
"VSS37"
$PN"85"6;
"VSS36"
$PN"83"6;
"VSS35"
$PN"81"6;
"VSS34"
$PN"79"6;
"VSS33"
$PN"77"6;
"VSS32"
$PN"75"6;
"VSS31"
$PN"73"6;
"VSS30"
$PN"71"6;
"VSS29"
$PN"69"6;
"VSS28"
$PN"67"6;
"VSS27"
$PN"65"6;
"VSS26"
$PN"63"6;
"VSS25"
$PN"61"6;
"VSS24"
$PN"59"6;
"VSS23"
$PN"57"6;
"VSS22"
$PN"54"6;
"VSS21"
$PN"52"6;
"VSS20"
$PN"50"6;
"VSS19"
$PN"48"6;
"VSS18"
$PN"46"6;
"VSS17"
$PN"43"6;
"VSS16"
$PN"41"6;
"VSS15"
$PN"39"6;
"VSS14"
$PN"37"6;
"VSS13"
$PN"35"6;
"VSS12"
$PN"32"6;
"VSS11"
$PN"30"6;
"VSS10"
$PN"28"6;
"VSS9"
$PN"26"6;
"VSS8"
$PN"24"6;
"VSS7"
$PN"21"6;
"VSS6"
$PN"19"6;
"VSS5"
$PN"17"6;
"VSS4"
$PN"15"6;
"VSS3"
$PN"13"6;
"VSS2"
$PN"10"6;
"VSS1"
$PN"8"6;
"VSS0"
$PN"6"6;
%"UNIVERSAL_GND"
"1","(5675,500)","0","logical_power","I176";
;
CDS_LIB"logical_power"
HDL_POWER"GND";
"A"6;
%"SCONN288_ADR50017P087CC"
"2","(1400,3200)","0","pure_quanta","I178";
;
PART_NUMBER"DFHST8FS460"
MATERIAL"IO"
VALUE"SCONN288_ADR50017-P087CC"
PART_TYPE"SMLF"
LOCATION"J6"
NEEDS_NO_SIZE"TRUE"
CDS_LMAN_SYM_OUTLINE"-600,1150,600,-1150"
CDS_LIB"pure_quanta"
$SEC"2"
CDS_SEC"2";
"DQS7_A_C||TDQS7_A_C \B"
$PN"178"34;
"DQS6_A_T||TDQS6_A_T"
$PN"168"53;
"DQS8_B_T||TDQS8_B_T"
$PN"283"61;
"DQS8_B_C||TDQS8_B_C \B"
$PN"282"42;
"DQS7_B_T||TDQS7_B_T"
$PN"272"62;
"DQS0_A_C \B"
$PN"12"40;
"DQS0_A_T"
$PN"11"59;
"DQS0_B_C \B"
$PN"105"48;
"DQS0_B_T"
$PN"104"69;
"DQS1_A_C \B"
$PN"23"38;
"DQS1_A_T"
$PN"22"58;
"DQS1_B_C \B"
$PN"116"49;
"DQS1_B_T"
$PN"115"68;
"DQS2_A_C \B"
$PN"34"39;
"DQS2_A_T"
$PN"33"57;
"DQS2_B_C \B"
$PN"127"47;
"DQS2_B_T"
$PN"126"67;
"DQS3_A_C \B"
$PN"45"37;
"DQS3_A_T"
$PN"44"56;
"DQS3_B_C \B"
$PN"138"46;
"DQS3_B_T"
$PN"137"66;
"DQS4_A_C \B"
$PN"56"36;
"DQS4_A_T"
$PN"55"55;
"DQS4_B_C \B"
$PN"238"45;
"DQS4_B_T"
$PN"239"65;
"DQS5_A_C||TDQS5_A_C||DQS5_A_T||TDQS5_A_T \B"
$PN"156"35;
"DQS5_A_T||TDQS5_A_T"
$PN"157"54;
"DQS5_B_C||TDQS5_B_C \B"
$PN"249"44;
"DQS5_B_T||TDQS5_B_T"
$PN"250"64;
"DQS6_A_C||TDQS6_A_C||DQS6_A_T||TDQS6_A_T \B"
$PN"167"33;
"DQS6_B_C||TDQS6_B_C \B"
$PN"260"30;
"DQS6_B_T||TDQS6_B_T"
$PN"261"63;
"DQS7_A_T||TDQS7_A_T"
$PN"179"52;
"DQS7_B_C||TDQS7_B_C \B"
$PN"271"43;
"DQS8_A_C||TDQS8_A_C \B"
$PN"189"32;
"DQS8_A_T||TDQS8_A_T"
$PN"190"51;
"DQS9_A_C||TDQS9_A_C \B"
$PN"200"31;
"DQS9_A_T||TDQS9_A_T"
$PN"201"50;
"DQS9_B_C||TDQS9_B_C \B"
$PN"94"41;
"DQS9_B_T||TDQS9_B_T||DBI4_B_N"
$PN"93"60;
%"Q_RES"
"1","(-3150,1500)","0","pure_quanta","I180";
;
PART_NUMBER"CS04992FB07"
MATERIAL"CHIP"
VALUE"49.9"
$LOCATION"R3880"
CDS_LIB"pure_quanta"
PACK_TYPE"0402LF"
TOLERANCE"1%"
WATTAGE"1/16W"
CDS_LOCATION"R3880"
$SEC"1"
CDS_SEC"1";
"B"
$PN"2"25;
"A"
$PN"1"22;
%"VCC_CORE"
"1","(-2925,2075)","0","logical_power","I20";
;
HDL_POWER"P3V3_AUX"
CDS_LIB"logical_power";
"A"2;
%"TAP"
"1","(-2100,2050)","2","standard","I21";
;
CDS_LIB"standard"
BODY_TYPE"PLUMBING"
HDL_TAP"TRUE";
"B \NAC \NWC"12;
"S \NAC"
BN"1"151;
%"TAP"
"1","(-2100,2000)","2","standard","I22";
;
CDS_LIB"standard"
BODY_TYPE"PLUMBING"
HDL_TAP"TRUE";
"B \NAC \NWC"12;
"S \NAC"
BN"0"150;
%"TAP"
"1","(-2100,2100)","2","standard","I23";
;
CDS_LIB"standard"
BODY_TYPE"PLUMBING"
HDL_TAP"TRUE";
"B \NAC \NWC"12;
"S \NAC"
BN"2"152;
%"TAP"
"1","(-2100,2200)","2","standard","I24";
;
CDS_LIB"standard"
BODY_TYPE"PLUMBING"
HDL_TAP"TRUE";
"B \NAC \NWC"12;
"S \NAC"
BN"4"83;
%"TAP"
"1","(-2100,2150)","2","standard","I25";
;
CDS_LIB"standard"
BODY_TYPE"PLUMBING"
HDL_TAP"TRUE";
"B \NAC \NWC"12;
"S \NAC"
BN"3"153;
%"TAP"
"1","(-2100,2300)","2","standard","I26";
;
CDS_LIB"standard"
BODY_TYPE"PLUMBING"
HDL_TAP"TRUE";
"B \NAC \NWC"12;
"S \NAC"
BN"6"154;
%"TAP"
"1","(-2100,2250)","2","standard","I27";
;
CDS_LIB"standard"
BODY_TYPE"PLUMBING"
HDL_TAP"TRUE";
"B \NAC \NWC"12;
"S \NAC"
BN"5"84;
%"TAP"
"1","(-2100,2350)","2","standard","I28";
;
CDS_LIB"standard"
BODY_TYPE"PLUMBING"
HDL_TAP"TRUE";
"B \NAC \NWC"12;
"S \NAC"
BN"7"173;
%"TAP"
"1","(-2100,2550)","2","standard","I29";
;
CDS_LIB"standard"
BODY_TYPE"PLUMBING"
HDL_TAP"TRUE";
"B \NAC \NWC"11;
"S \NAC"
BN"2"156;
%"TAP"
"1","(-2100,2450)","2","standard","I30";
;
CDS_LIB"standard"
BODY_TYPE"PLUMBING"
HDL_TAP"TRUE";
"B \NAC \NWC"11;
"S \NAC"
BN"0"155;
%"TAP"
"1","(-2100,2500)","2","standard","I31";
;
CDS_LIB"standard"
BODY_TYPE"PLUMBING"
HDL_TAP"TRUE";
"B \NAC \NWC"11;
"S \NAC"
BN"1"174;
%"TAP"
"1","(-2100,2600)","2","standard","I32";
;
CDS_LIB"standard"
BODY_TYPE"PLUMBING"
HDL_TAP"TRUE";
"B \NAC \NWC"11;
"S \NAC"
BN"3"157;
%"TAP"
"1","(-2100,2700)","2","standard","I33";
;
CDS_LIB"standard"
BODY_TYPE"PLUMBING"
HDL_TAP"TRUE";
"B \NAC \NWC"11;
"S \NAC"
BN"5"158;
%"TAP"
"1","(-2100,2650)","2","standard","I34";
;
CDS_LIB"standard"
BODY_TYPE"PLUMBING"
HDL_TAP"TRUE";
"B \NAC \NWC"11;
"S \NAC"
BN"4"175;
%"TAP"
"1","(-2100,2800)","2","standard","I35";
;
CDS_LIB"standard"
BODY_TYPE"PLUMBING"
HDL_TAP"TRUE";
"B \NAC \NWC"11;
"S \NAC"
BN"7"176;
%"TAP"
"1","(-2100,2750)","2","standard","I36";
;
CDS_LIB"standard"
BODY_TYPE"PLUMBING"
HDL_TAP"TRUE";
"B \NAC \NWC"11;
"S \NAC"
BN"6"159;
%"TAP"
"1","(-2100,3600)","2","standard","I37";
;
CDS_LIB"standard"
BODY_TYPE"PLUMBING"
HDL_TAP"TRUE";
"B \NAC \NWC"14;
"S \NAC"
BN"2"168;
%"TAP"
"1","(-2100,3500)","2","standard","I38";
;
CDS_LIB"standard"
BODY_TYPE"PLUMBING"
HDL_TAP"TRUE";
"B \NAC \NWC"14;
"S \NAC"
BN"0"171;
%"TAP"
"1","(-2100,3550)","2","standard","I39";
;
CDS_LIB"standard"
BODY_TYPE"PLUMBING"
HDL_TAP"TRUE";
"B \NAC \NWC"14;
"S \NAC"
BN"1"76;
%"TAP"
"1","(-2100,3800)","2","standard","I40";
;
CDS_LIB"standard"
BODY_TYPE"PLUMBING"
HDL_TAP"TRUE";
"B \NAC \NWC"14;
"S \NAC"
BN"6"160;
%"TAP"
"1","(-2100,3700)","2","standard","I41";
;
CDS_LIB"standard"
BODY_TYPE"PLUMBING"
HDL_TAP"TRUE";
"B \NAC \NWC"14;
"S \NAC"
BN"4"164;
%"TAP"
"1","(-2100,3650)","2","standard","I42";
;
CDS_LIB"standard"
BODY_TYPE"PLUMBING"
HDL_TAP"TRUE";
"B \NAC \NWC"14;
"S \NAC"
BN"3"166;
%"TAP"
"1","(-2100,3750)","2","standard","I43";
;
CDS_LIB"standard"
BODY_TYPE"PLUMBING"
HDL_TAP"TRUE";
"B \NAC \NWC"14;
"S \NAC"
BN"5"162;
%"UNIVERSAL_GND"
"1","(-1875,-175)","0","logical_power","I44";
;
CDS_LIB"logical_power"
HDL_POWER"GND";
"A"5;
%"Q_RES"
"2","(-1875,50)","0","pure_quanta","I45";
;
PART_NUMBER"CS38452FB05"
VALUE"84.5K"
PACK_TYPE"0402LF"
MATERIAL"CHIP"
WATTAGE"1/16W"
TOLERANCE"1%"
$LOCATION"R31"
CDS_LIB"pure_quanta"
CDS_LOCATION"R31"
$SEC"1"
CDS_SEC"1";
"A"
$PN"1"178;
"B"
$PN"2"5;
%"SCONN288_ADR50017P087CC"
"1","(-1275,2475)","0","pure_quanta","I46";
;
PART_NUMBER"DFHST8FS460"
MATERIAL"IO"
PART_TYPE"SMLF"
VALUE"SCONN288_ADR50017-P087CC"
$LOCATION"J6"
NEEDS_NO_SIZE"TRUE"
CDS_LMAN_SYM_OUTLINE"-450,1875,450,-1875"
CDS_LIB"pure_quanta"
CDS_LOCATION"J6"
$SEC"1"
CDS_SEC"1";
"DQ31_A"
$PN"194"177;
"CB7_A"
$PN"205"176;
"CB4_A"
$PN"58"175;
"CB1_A"
$PN"53"174;
"CB7_B"
$PN"236"173;
"ALERT_N \B"
$PN"62"23;
"CA0_A"
$PN"66"172;
"CA0_B"
$PN"76"171;
"CA1_A"
$PN"211"170;
"CA1_B"
$PN"221"76;
"CA2_A"
$PN"68"169;
"CA2_B"
$PN"78"168;
"CA3_A"
$PN"213"167;
"CA3_B"
$PN"223"166;
"CA4_A"
$PN"70"165;
"CA4_B"
$PN"80"164;
"CA5_A"
$PN"215"163;
"CA5_B"
$PN"225"162;
"CA6_A"
$PN"72"161;
"CA6_B"
$PN"82"160;
"CB6_A"
$PN"203"159;
"CB5_A"
$PN"60"158;
"CB3_A"
$PN"198"157;
"CB2_A"
$PN"196"156;
"CB0_A"
$PN"51"155;
"CB6_B"
$PN"234"154;
"CB5_B"
$PN"91"84;
"CB4_B"
$PN"89"83;
"CB3_B"
$PN"243"153;
"CB2_B"
$PN"241"152;
"CB1_B"
$PN"98"151;
"CB0_B"
$PN"96"150;
"CK_C \B"
$PN"218"82;
"CK_T"
$PN"217"70;
"CS0_A_N"
$PN"64"80;
"CS0_B_N"
$PN"84"29;
"CS1_A_N"
$PN"209"79;
"CS1_B_N"
$PN"229"81;
"DQ30_A"
$PN"192"149;
"DQ29_A"
$PN"49"148;
"DQ28_A"
$PN"47"147;
"DQ27_A"
$PN"187"146;
"DQ26_A"
$PN"185"145;
"DQ25_A"
$PN"42"144;
"DQ24_A"
$PN"40"143;
"DQ23_A"
$PN"183"142;
"DQ22_A"
$PN"181"141;
"DQ21_A"
$PN"38"140;
"DQ20_A"
$PN"36"139;
"DQ19_A"
$PN"176"138;
"DQ18_A"
$PN"174"137;
"DQ17_A"
$PN"31"136;
"DQ16_A"
$PN"29"135;
"DQ15_A"
$PN"172"134;
"DQ14_A"
$PN"170"133;
"DQ13_A"
$PN"27"132;
"DQ12_A"
$PN"25"131;
"DQ11_A"
$PN"165"130;
"DQ10_A"
$PN"163"129;
"DQ9_A"
$PN"20"128;
"DQ8_A"
$PN"18"127;
"DQ7_A"
$PN"161"126;
"DQ6_A"
$PN"159"125;
"DQ5_A"
$PN"16"124;
"DQ4_A"
$PN"14"123;
"DQ3_A"
$PN"154"122;
"DQ2_A"
$PN"152"121;
"DQ1_A"
$PN"9"120;
"DQ0_A"
$PN"7"119;
"DQ31_B"
$PN"287"118;
"DQ30_B"
$PN"285"117;
"DQ29_B"
$PN"142"116;
"DQ28_B"
$PN"140"115;
"DQ27_B"
$PN"280"114;
"DQ26_B"
$PN"278"113;
"DQ25_B"
$PN"135"112;
"DQ24_B"
$PN"133"111;
"DQ23_B"
$PN"276"110;
"DQ22_B"
$PN"274"109;
"DQ21_B"
$PN"131"108;
"DQ20_B"
$PN"129"85;
"DQ19_B"
$PN"269"107;
"DQ18_B"
$PN"267"106;
"DQ17_B"
$PN"124"105;
"DQ16_B"
$PN"122"104;
"DQ15_B"
$PN"265"103;
"DQ14_B"
$PN"263"102;
"DQ13_B"
$PN"120"101;
"DQ12_B"
$PN"118"100;
"DQ11_B"
$PN"258"99;
"DQ10_B"
$PN"256"98;
"DQ9_B"
$PN"113"97;
"DQ8_B"
$PN"111"96;
"DQ7_B"
$PN"254"75;
"DQ6_B"
$PN"252"86;
"DQ5_B"
$PN"109"95;
"DQ4_B"
$PN"107"94;
"DQ3_B"
$PN"247"93;
"DQ2_B"
$PN"245"92;
"DQ1_B"
$PN"102"91;
"DQ0_B"
$PN"100"90;
"HSA"
$PN"148"20;
"HSCL"
$PN"4"22;
"HSDA"
$PN"5"21;
"LBD||RSP_A_N"
$PN"86"89;
"LBS||RSP_B_N"
$PN"87"88;
"PAR_A"
$PN"74"77;
"PAR_B"
$PN"227"78;
"PWR_GOOD||FAIL_N"
$PN"147"28;
"RESET_N \B"
$PN"207"24;
"RFU6"
$PN"232"74;
"RFU5"
$PN"231"27;
"RFU4"
$PN"220"26;
"RFU3"
$PN"150"71;
"RFU2"
$PN"149"72;
"RFU1"
$PN"144"87;
"RFU0"
$PN"2"73;
"VIN_MGMT"
$PN"3"2;
%"TAP"
"1","(-450,1050)","0","standard","I47";
;
CDS_LIB"standard"
BODY_TYPE"PLUMBING"
HDL_TAP"TRUE";
"B \NAC \NWC"15;
"S \NAC"
BN"1"91;
%"TAP"
"1","(-450,1000)","0","standard","I48";
;
CDS_LIB"standard"
BODY_TYPE"PLUMBING"
HDL_TAP"TRUE";
"B \NAC \NWC"15;
"S \NAC"
BN"0"90;
%"TAP"
"1","(-450,1100)","0","standard","I49";
;
CDS_LIB"standard"
BODY_TYPE"PLUMBING"
HDL_TAP"TRUE";
"B \NAC \NWC"15;
"S \NAC"
BN"2"92;
%"TAP"
"1","(-450,1200)","0","standard","I50";
;
CDS_LIB"standard"
BODY_TYPE"PLUMBING"
HDL_TAP"TRUE";
"B \NAC \NWC"15;
"S \NAC"
BN"4"94;
%"TAP"
"1","(-450,1150)","0","standard","I51";
;
CDS_LIB"standard"
BODY_TYPE"PLUMBING"
HDL_TAP"TRUE";
"B \NAC \NWC"15;
"S \NAC"
BN"3"93;
%"TAP"
"1","(-450,1300)","0","standard","I52";
;
CDS_LIB"standard"
BODY_TYPE"PLUMBING"
HDL_TAP"TRUE";
"B \NAC \NWC"15;
"S \NAC"
BN"6"86;
%"TAP"
"1","(-450,1250)","0","standard","I53";
;
CDS_LIB"standard"
BODY_TYPE"PLUMBING"
HDL_TAP"TRUE";
"B \NAC \NWC"15;
"S \NAC"
BN"5"95;
%"TAP"
"1","(-450,1350)","0","standard","I54";
;
CDS_LIB"standard"
BODY_TYPE"PLUMBING"
HDL_TAP"TRUE";
"B \NAC \NWC"15;
"S \NAC"
BN"7"75;
%"TAP"
"1","(-450,1400)","0","standard","I55";
;
CDS_LIB"standard"
BODY_TYPE"PLUMBING"
HDL_TAP"TRUE";
"B \NAC \NWC"15;
"S \NAC"
BN"8"96;
%"TAP"
"1","(-450,1450)","0","standard","I56";
;
CDS_LIB"standard"
BODY_TYPE"PLUMBING"
HDL_TAP"TRUE";
"B \NAC \NWC"15;
"S \NAC"
BN"9"97;
%"TAP"
"1","(-450,1550)","0","standard","I57";
;
CDS_LIB"standard"
BODY_TYPE"PLUMBING"
HDL_TAP"TRUE";
"B \NAC \NWC"15;
"S \NAC"
BN"11"99;
%"TAP"
"1","(-450,1500)","0","standard","I58";
;
CDS_LIB"standard"
BODY_TYPE"PLUMBING"
HDL_TAP"TRUE";
"B \NAC \NWC"15;
"S \NAC"
BN"10"98;
%"TAP"
"1","(-450,1600)","0","standard","I59";
;
CDS_LIB"standard"
BODY_TYPE"PLUMBING"
HDL_TAP"TRUE";
"B \NAC \NWC"15;
"S \NAC"
BN"12"100;
%"TAP"
"1","(-450,1650)","0","standard","I60";
;
CDS_LIB"standard"
BODY_TYPE"PLUMBING"
HDL_TAP"TRUE";
"B \NAC \NWC"15;
"S \NAC"
BN"13"101;
%"TAP"
"1","(-450,1700)","0","standard","I61";
;
CDS_LIB"standard"
BODY_TYPE"PLUMBING"
HDL_TAP"TRUE";
"B \NAC \NWC"15;
"S \NAC"
BN"14"102;
%"TAP"
"1","(-450,1800)","0","standard","I62";
;
CDS_LIB"standard"
BODY_TYPE"PLUMBING"
HDL_TAP"TRUE";
"B \NAC \NWC"15;
"S \NAC"
BN"16"104;
%"TAP"
"1","(-450,1750)","0","standard","I63";
;
CDS_LIB"standard"
BODY_TYPE"PLUMBING"
HDL_TAP"TRUE";
"B \NAC \NWC"15;
"S \NAC"
BN"15"103;
%"TAP"
"1","(-450,1900)","0","standard","I64";
;
CDS_LIB"standard"
BODY_TYPE"PLUMBING"
HDL_TAP"TRUE";
"B \NAC \NWC"15;
"S \NAC"
BN"18"106;
%"TAP"
"1","(-450,1850)","0","standard","I65";
;
CDS_LIB"standard"
BODY_TYPE"PLUMBING"
HDL_TAP"TRUE";
"B \NAC \NWC"15;
"S \NAC"
BN"17"105;
%"TAP"
"1","(-450,1950)","0","standard","I66";
;
CDS_LIB"standard"
BODY_TYPE"PLUMBING"
HDL_TAP"TRUE";
"B \NAC \NWC"15;
"S \NAC"
BN"19"107;
%"TAP"
"1","(-450,2000)","0","standard","I67";
;
CDS_LIB"standard"
BODY_TYPE"PLUMBING"
HDL_TAP"TRUE";
"B \NAC \NWC"15;
"S \NAC"
BN"20"85;
%"TAP"
"1","(-450,2100)","0","standard","I68";
;
CDS_LIB"standard"
BODY_TYPE"PLUMBING"
HDL_TAP"TRUE";
"B \NAC \NWC"15;
"S \NAC"
BN"22"109;
%"TAP"
"1","(-450,2050)","0","standard","I69";
;
CDS_LIB"standard"
BODY_TYPE"PLUMBING"
HDL_TAP"TRUE";
"B \NAC \NWC"15;
"S \NAC"
BN"21"108;
%"TAP"
"1","(-450,2150)","0","standard","I70";
;
CDS_LIB"standard"
BODY_TYPE"PLUMBING"
HDL_TAP"TRUE";
"B \NAC \NWC"15;
"S \NAC"
BN"23"110;
%"TAP"
"1","(-450,2200)","0","standard","I71";
;
CDS_LIB"standard"
BODY_TYPE"PLUMBING"
HDL_TAP"TRUE";
"B \NAC \NWC"15;
"S \NAC"
BN"24"111;
%"TAP"
"1","(-450,2250)","0","standard","I72";
;
CDS_LIB"standard"
BODY_TYPE"PLUMBING"
HDL_TAP"TRUE";
"B \NAC \NWC"15;
"S \NAC"
BN"25"112;
%"TAP"
"1","(-450,2350)","0","standard","I73";
;
CDS_LIB"standard"
BODY_TYPE"PLUMBING"
HDL_TAP"TRUE";
"B \NAC \NWC"15;
"S \NAC"
BN"27"114;
%"TAP"
"1","(-450,2300)","0","standard","I74";
;
CDS_LIB"standard"
BODY_TYPE"PLUMBING"
HDL_TAP"TRUE";
"B \NAC \NWC"15;
"S \NAC"
BN"26"113;
%"TAP"
"1","(-450,2400)","0","standard","I75";
;
CDS_LIB"standard"
BODY_TYPE"PLUMBING"
HDL_TAP"TRUE";
"B \NAC \NWC"15;
"S \NAC"
BN"28"115;
%"TAP"
"1","(-450,2450)","0","standard","I76";
;
CDS_LIB"standard"
BODY_TYPE"PLUMBING"
HDL_TAP"TRUE";
"B \NAC \NWC"15;
"S \NAC"
BN"29"116;
%"TAP"
"1","(-450,2500)","0","standard","I77";
;
CDS_LIB"standard"
BODY_TYPE"PLUMBING"
HDL_TAP"TRUE";
"B \NAC \NWC"15;
"S \NAC"
BN"30"117;
%"TAP"
"1","(-450,2550)","0","standard","I78";
;
CDS_LIB"standard"
BODY_TYPE"PLUMBING"
HDL_TAP"TRUE";
"B \NAC \NWC"15;
"S \NAC"
BN"31"118;
%"TAP"
"1","(-450,2650)","0","standard","I79";
;
CDS_LIB"standard"
BODY_TYPE"PLUMBING"
HDL_TAP"TRUE";
"B \NAC \NWC"10;
"S \NAC"
BN"0"119;
%"TAP"
"1","(-450,2700)","0","standard","I80";
;
CDS_LIB"standard"
BODY_TYPE"PLUMBING"
HDL_TAP"TRUE";
"B \NAC \NWC"10;
"S \NAC"
BN"1"120;
%"TAP"
"1","(-450,2800)","0","standard","I81";
;
CDS_LIB"standard"
BODY_TYPE"PLUMBING"
HDL_TAP"TRUE";
"B \NAC \NWC"10;
"S \NAC"
BN"3"122;
%"TAP"
"1","(-450,2750)","0","standard","I82";
;
CDS_LIB"standard"
BODY_TYPE"PLUMBING"
HDL_TAP"TRUE";
"B \NAC \NWC"10;
"S \NAC"
BN"2"121;
%"TAP"
"1","(-450,2850)","0","standard","I83";
;
CDS_LIB"standard"
BODY_TYPE"PLUMBING"
HDL_TAP"TRUE";
"B \NAC \NWC"10;
"S \NAC"
BN"4"123;
%"TAP"
"1","(-450,2900)","0","standard","I84";
;
CDS_LIB"standard"
BODY_TYPE"PLUMBING"
HDL_TAP"TRUE";
"B \NAC \NWC"10;
"S \NAC"
BN"5"124;
%"TAP"
"1","(-450,2950)","0","standard","I85";
;
CDS_LIB"standard"
BODY_TYPE"PLUMBING"
HDL_TAP"TRUE";
"B \NAC \NWC"10;
"S \NAC"
BN"6"125;
%"TAP"
"1","(-450,3000)","0","standard","I86";
;
CDS_LIB"standard"
BODY_TYPE"PLUMBING"
HDL_TAP"TRUE";
"B \NAC \NWC"10;
"S \NAC"
BN"7"126;
%"TAP"
"1","(-450,3100)","0","standard","I87";
;
CDS_LIB"standard"
BODY_TYPE"PLUMBING"
HDL_TAP"TRUE";
"B \NAC \NWC"10;
"S \NAC"
BN"9"128;
%"TAP"
"1","(-450,3050)","0","standard","I88";
;
CDS_LIB"standard"
BODY_TYPE"PLUMBING"
HDL_TAP"TRUE";
"B \NAC \NWC"10;
"S \NAC"
BN"8"127;
%"TAP"
"1","(-450,3150)","0","standard","I89";
;
CDS_LIB"standard"
BODY_TYPE"PLUMBING"
HDL_TAP"TRUE";
"B \NAC \NWC"10;
"S \NAC"
BN"10"129;
%"TAP"
"1","(-450,3250)","0","standard","I90";
;
CDS_LIB"standard"
BODY_TYPE"PLUMBING"
HDL_TAP"TRUE";
"B \NAC \NWC"10;
"S \NAC"
BN"12"131;
%"TAP"
"1","(-450,3200)","0","standard","I91";
;
CDS_LIB"standard"
BODY_TYPE"PLUMBING"
HDL_TAP"TRUE";
"B \NAC \NWC"10;
"S \NAC"
BN"11"130;
%"TAP"
"1","(-450,3350)","0","standard","I92";
;
CDS_LIB"standard"
BODY_TYPE"PLUMBING"
HDL_TAP"TRUE";
"B \NAC \NWC"10;
"S \NAC"
BN"14"133;
%"TAP"
"1","(-450,3300)","0","standard","I93";
;
CDS_LIB"standard"
BODY_TYPE"PLUMBING"
HDL_TAP"TRUE";
"B \NAC \NWC"10;
"S \NAC"
BN"13"132;
%"TAP"
"1","(-450,3400)","0","standard","I94";
;
CDS_LIB"standard"
BODY_TYPE"PLUMBING"
HDL_TAP"TRUE";
"B \NAC \NWC"10;
"S \NAC"
BN"15"134;
%"TAP"
"1","(-450,3500)","0","standard","I95";
;
CDS_LIB"standard"
BODY_TYPE"PLUMBING"
HDL_TAP"TRUE";
"B \NAC \NWC"10;
"S \NAC"
BN"17"136;
%"TAP"
"1","(-450,3450)","0","standard","I96";
;
CDS_LIB"standard"
BODY_TYPE"PLUMBING"
HDL_TAP"TRUE";
"B \NAC \NWC"10;
"S \NAC"
BN"16"135;
%"TAP"
"1","(-450,3600)","0","standard","I97";
;
CDS_LIB"standard"
BODY_TYPE"PLUMBING"
HDL_TAP"TRUE";
"B \NAC \NWC"10;
"S \NAC"
BN"19"138;
%"TAP"
"1","(-450,3550)","0","standard","I98";
;
CDS_LIB"standard"
BODY_TYPE"PLUMBING"
HDL_TAP"TRUE";
"B \NAC \NWC"10;
"S \NAC"
BN"18"137;
%"TAP"
"1","(-450,3650)","0","standard","I99";
;
CDS_LIB"standard"
BODY_TYPE"PLUMBING"
HDL_TAP"TRUE";
"B \NAC \NWC"10;
"S \NAC"
BN"20"139;
END.
